(kicad_pcb
	(version 20260206)
	(generator "pcbnew")
	(generator_version "10.0")
	(general
		(thickness 1.6)
		(legacy_teardrops no)
	)
	(paper "A4")
	(title_block
		(title "v1-chassis-manager — T6M_CM_d_v01_1031_1645.brd")
		(comment 1 "Open CloudServer (Microsoft) / footprints 1943-1952 of 2512")
	)
	(layers
		(0 "F.Cu" signal "TOP")
		(4 "In1.Cu" signal "GND1")
		(6 "In2.Cu" signal "IN1")
		(8 "In3.Cu" signal "VCC1")
		(10 "In4.Cu" signal "VCC2")
		(12 "In5.Cu" signal "GND2")
		(14 "In6.Cu" signal "IN2")
		(16 "In7.Cu" signal "IN3")
		(18 "In8.Cu" signal "GND3")
		(2 "B.Cu" signal "BOTTOM")
		(9 "F.Adhes" user "F.Adhesive")
		(11 "B.Adhes" user "B.Adhesive")
		(13 "F.Paste" user "Package Geometry/Pastemask Top")
		(15 "B.Paste" user "Package Geometry/Pastemask Bottom")
		(5 "F.SilkS" user "Ref Des/Silkscreen Top")
		(7 "B.SilkS" user "Ref Des/Silkscreen Bottom")
		(1 "F.Mask" user "Board Geometry/Soldermask Top")
		(3 "B.Mask" user "Board Geometry/Soldermask Bottom")
		(17 "Dwgs.User" user "User.Drawings")
		(19 "Cmts.User" user "User.Comments")
		(21 "Eco1.User" user "User.Eco1")
		(23 "Eco2.User" user "User.Eco2")
		(25 "Edge.Cuts" user "Board Geometry/Outline")
		(27 "Margin" user)
		(31 "F.CrtYd" user "Package Geometry/Place Bound Top")
		(29 "B.CrtYd" user "Package Geometry/Place Bound Bottom")
		(35 "F.Fab" user "Ref Des/Assembly Top")
		(33 "B.Fab" user "Ref Des/Assembly Bottom")
	)
	(footprint ""
		(layer "B.Cu")
		(at 110.70717 -182.658512 180)
		(property "Reference" "R970"
			(at 21.496528 -32.262826 0)
			(unlocked yes)
			(layer "B.SilkS")
			(effects
				(font
					(size 0.7874 0.5842)
					(thickness 0.1524)
				)
				(justify left mirror)
			)
		)
		(property "Value" ""
			(at 0 0 0)
			(layer "B.Fab")
			(effects
				(font
					(size 1.27 1.27)
				)
				(justify mirror)
			)
		)
		(duplicate_pad_numbers_are_jumpers no)
		(fp_line
			(start 0.7874 0.4064)
			(end 0.7874 -0.4064)
			(stroke
				(width 0.1524)
				(type default)
			)
			(layer "B.SilkS")
		)
		(fp_line
			(start 0.7874 -0.4064)
			(end -0.7874 -0.4064)
			(stroke
				(width 0.1524)
				(type default)
			)
			(layer "B.SilkS")
		)
		(fp_line
			(start -0.7874 0.4064)
			(end 0.7874 0.4064)
			(stroke
				(width 0.1524)
				(type default)
			)
			(layer "B.SilkS")
		)
		(fp_line
			(start -0.7874 -0.4064)
			(end -0.7874 0.4064)
			(stroke
				(width 0.1524)
				(type default)
			)
			(layer "B.SilkS")
		)
		(fp_poly
			(pts
				(xy 0.508 0.2794) (xy 0.508 0.2286) (xy 0.635 0.2286) (xy 0.635 -0.254) (xy 0.5334 -0.254) (xy 0.5334 -0.2794)
				(xy -0.5334 -0.2794) (xy -0.5334 -0.254) (xy -0.635 -0.254) (xy -0.635 0.254) (xy -0.5334 0.254)
				(xy -0.5334 0.2794)
			)
			(stroke
				(width 0)
				(type default)
			)
			(fill no)
			(layer "B.CrtYd")
		)
		(pad "1" smd rect
			(at -0.40005 0)
			(size 0.4572 0.508)
			(layers "B.Cu" "B.Mask" "B.Paste")
			(net "UART_T7_NODE3_TXD")
		)
		(pad "2" smd rect
			(at 0.40005 0)
			(size 0.4572 0.508)
			(layers "B.Cu" "B.Mask" "B.Paste")
			(net "UART_T7_NODE3_TXD_R")
		)
	)
	(footprint ""
		(layer "B.Cu")
		(at 63.922656 -143.802862)
		(property "Reference" "C257"
			(at 4.321556 0.176276 0)
			(unlocked yes)
			(layer "B.SilkS")
			(effects
				(font
					(size 0.7874 0.5842)
					(thickness 0.1524)
				)
				(justify left mirror)
			)
		)
		(property "Value" ""
			(at 0 0 0)
			(layer "B.Fab")
			(effects
				(font
					(size 1.27 1.27)
				)
				(justify mirror)
			)
		)
		(duplicate_pad_numbers_are_jumpers no)
		(fp_line
			(start -0.7874 -0.4064)
			(end -0.7874 0.4064)
			(stroke
				(width 0.1524)
				(type default)
			)
			(layer "B.SilkS")
		)
		(fp_line
			(start -0.7874 0.4064)
			(end 0.7874 0.4064)
			(stroke
				(width 0.1524)
				(type default)
			)
			(layer "B.SilkS")
		)
		(fp_line
			(start 0 0.381)
			(end 0 -0.381)
			(stroke
				(width 0.1524)
				(type default)
			)
			(layer "B.SilkS")
		)
		(fp_line
			(start 0.7874 -0.4064)
			(end -0.7874 -0.4064)
			(stroke
				(width 0.1524)
				(type default)
			)
			(layer "B.SilkS")
		)
		(fp_line
			(start 0.7874 0.4064)
			(end 0.7874 -0.4064)
			(stroke
				(width 0.1524)
				(type default)
			)
			(layer "B.SilkS")
		)
		(fp_poly
			(pts
				(xy 0.5334 0.254) (xy 0.635 0.254) (xy 0.635 0.2286) (xy 0.635 -0.254) (xy 0.5334 -0.254) (xy 0.5334 -0.2794)
				(xy -0.5334 -0.2794) (xy -0.5334 -0.254) (xy -0.635 -0.254) (xy -0.635 0.254) (xy -0.5334 0.254)
				(xy -0.5334 0.2794) (xy 0.508 0.2794) (xy 0.5334 0.2794)
			)
			(stroke
				(width 0)
				(type default)
			)
			(fill no)
			(layer "B.CrtYd")
		)
		(pad "1" smd rect
			(at -0.40005 0 180)
			(size 0.4572 0.508)
			(layers "B.Cu" "B.Mask" "B.Paste")
			(net "BMC_NODE1_ADCAV33")
		)
		(pad "2" smd rect
			(at 0.40005 0 180)
			(size 0.4572 0.508)
			(layers "B.Cu" "B.Mask" "B.Paste")
			(net "GND")
		)
	)
	(footprint ""
		(layer "B.Cu")
		(at 135.407908 -122.841258 180)
		(property "Reference" "R5"
			(at -2.329688 -0.027178 0)
			(unlocked yes)
			(layer "B.SilkS")
			(effects
				(font
					(size 0.7874 0.5842)
					(thickness 0.1524)
				)
				(justify left mirror)
			)
		)
		(property "Value" ""
			(at 0 0 0)
			(layer "B.Fab")
			(effects
				(font
					(size 1.27 1.27)
				)
				(justify mirror)
			)
		)
		(duplicate_pad_numbers_are_jumpers no)
		(fp_line
			(start 0.7874 0.4064)
			(end 0.7874 -0.4064)
			(stroke
				(width 0.1524)
				(type default)
			)
			(layer "B.SilkS")
		)
		(fp_line
			(start 0.7874 -0.4064)
			(end -0.7874 -0.4064)
			(stroke
				(width 0.1524)
				(type default)
			)
			(layer "B.SilkS")
		)
		(fp_line
			(start -0.7874 0.4064)
			(end 0.7874 0.4064)
			(stroke
				(width 0.1524)
				(type default)
			)
			(layer "B.SilkS")
		)
		(fp_line
			(start -0.7874 -0.4064)
			(end -0.7874 0.4064)
			(stroke
				(width 0.1524)
				(type default)
			)
			(layer "B.SilkS")
		)
		(fp_poly
			(pts
				(xy 0.508 0.2794) (xy 0.508 0.2286) (xy 0.635 0.2286) (xy 0.635 -0.254) (xy 0.5334 -0.254) (xy 0.5334 -0.2794)
				(xy -0.5334 -0.2794) (xy -0.5334 -0.254) (xy -0.635 -0.254) (xy -0.635 0.254) (xy -0.5334 0.254)
				(xy -0.5334 0.2794)
			)
			(stroke
				(width 0)
				(type default)
			)
			(fill no)
			(layer "B.CrtYd")
		)
		(pad "1" smd rect
			(at -0.40005 0)
			(size 0.4572 0.508)
			(layers "B.Cu" "B.Mask" "B.Paste")
			(net "P3V3_CLK_NODE1")
		)
		(pad "2" smd rect
			(at 0.40005 0)
			(size 0.4572 0.508)
			(layers "B.Cu" "B.Mask" "B.Paste")
			(net "PCI_STP_NODE1")
		)
	)
	(footprint ""
		(layer "B.Cu")
		(at 73.00976 -188.126624 90)
		(property "Reference" "R914"
			(at 4.318254 -0.320802 270)
			(unlocked yes)
			(layer "B.SilkS")
			(effects
				(font
					(size 0.7874 0.5842)
					(thickness 0.1524)
				)
				(justify left mirror)
			)
		)
		(property "Value" ""
			(at 0 0 90)
			(layer "B.Fab")
			(effects
				(font
					(size 1.27 1.27)
				)
				(justify mirror)
			)
		)
		(duplicate_pad_numbers_are_jumpers no)
		(fp_line
			(start 0.7874 -0.4064)
			(end -0.7874 -0.4064)
			(stroke
				(width 0.1524)
				(type default)
			)
			(layer "B.SilkS")
		)
		(fp_line
			(start -0.7874 -0.4064)
			(end -0.7874 0.4064)
			(stroke
				(width 0.1524)
				(type default)
			)
			(layer "B.SilkS")
		)
		(fp_line
			(start 0.7874 0.4064)
			(end 0.7874 -0.4064)
			(stroke
				(width 0.1524)
				(type default)
			)
			(layer "B.SilkS")
		)
		(fp_line
			(start -0.7874 0.4064)
			(end 0.7874 0.4064)
			(stroke
				(width 0.1524)
				(type default)
			)
			(layer "B.SilkS")
		)
		(fp_poly
			(pts
				(xy 0.508 0.2794) (xy 0.508 0.2286) (xy 0.635 0.2286) (xy 0.635 -0.254) (xy 0.5334 -0.254) (xy 0.5334 -0.2794)
				(xy -0.5334 -0.2794) (xy -0.5334 -0.254) (xy -0.635 -0.254) (xy -0.635 0.254) (xy -0.5334 0.254)
				(xy -0.5334 0.2794)
			)
			(stroke
				(width 0)
				(type default)
			)
			(fill no)
			(layer "B.CrtYd")
		)
		(pad "1" smd rect
			(at -0.40005 0 270)
			(size 0.4572 0.508)
			(layers "B.Cu" "B.Mask" "B.Paste")
			(net "UART_T3_NODE2_RXD")
		)
		(pad "2" smd rect
			(at 0.40005 0 270)
			(size 0.4572 0.508)
			(layers "B.Cu" "B.Mask" "B.Paste")
			(net "UART_T3_NODE2_RXD_R")
		)
	)
	(footprint ""
		(layer "B.Cu")
		(at 58.279538 -80.420718)
		(property "Reference" "C46"
			(at -13.440918 30.936184 0)
			(unlocked yes)
			(layer "B.SilkS")
			(effects
				(font
					(size 0.7874 0.5842)
					(thickness 0.1524)
				)
				(justify left mirror)
			)
		)
		(property "Value" ""
			(at 0 0 0)
			(layer "B.Fab")
			(effects
				(font
					(size 1.27 1.27)
				)
				(justify mirror)
			)
		)
		(duplicate_pad_numbers_are_jumpers no)
		(fp_line
			(start -0.7874 -0.4064)
			(end -0.7874 0.4064)
			(stroke
				(width 0.1524)
				(type default)
			)
			(layer "B.SilkS")
		)
		(fp_line
			(start -0.7874 0.4064)
			(end 0.7874 0.4064)
			(stroke
				(width 0.1524)
				(type default)
			)
			(layer "B.SilkS")
		)
		(fp_line
			(start 0 0.381)
			(end 0 -0.381)
			(stroke
				(width 0.1524)
				(type default)
			)
			(layer "B.SilkS")
		)
		(fp_line
			(start 0.7874 -0.4064)
			(end -0.7874 -0.4064)
			(stroke
				(width 0.1524)
				(type default)
			)
			(layer "B.SilkS")
		)
		(fp_line
			(start 0.7874 0.4064)
			(end 0.7874 -0.4064)
			(stroke
				(width 0.1524)
				(type default)
			)
			(layer "B.SilkS")
		)
		(fp_poly
			(pts
				(xy 0.5334 0.254) (xy 0.635 0.254) (xy 0.635 0.2286) (xy 0.635 -0.254) (xy 0.5334 -0.254) (xy 0.5334 -0.2794)
				(xy -0.5334 -0.2794) (xy -0.5334 -0.254) (xy -0.635 -0.254) (xy -0.635 0.254) (xy -0.5334 0.254)
				(xy -0.5334 0.2794) (xy 0.508 0.2794) (xy 0.5334 0.2794)
			)
			(stroke
				(width 0)
				(type default)
			)
			(fill no)
			(layer "B.CrtYd")
		)
		(pad "1" smd rect
			(at -0.40005 0 180)
			(size 0.4572 0.508)
			(layers "B.Cu" "B.Mask" "B.Paste")
			(net "P1V05_NODE1")
		)
		(pad "2" smd rect
			(at 0.40005 0 180)
			(size 0.4572 0.508)
			(layers "B.Cu" "B.Mask" "B.Paste")
			(net "GND")
		)
	)
	(footprint ""
		(layer "B.Cu")
		(at 138.541252 -135.84555 -90)
		(property "Reference" "C870"
			(at 5.04825 0.03937 270)
			(unlocked yes)
			(layer "B.SilkS")
			(effects
				(font
					(size 0.7874 0.5842)
					(thickness 0.1524)
				)
				(justify left mirror)
			)
		)
		(property "Value" ""
			(at 0 0 90)
			(layer "B.Fab")
			(effects
				(font
					(size 1.27 1.27)
				)
				(justify mirror)
			)
		)
		(duplicate_pad_numbers_are_jumpers no)
		(fp_line
			(start -0.7874 0.4064)
			(end 0.7874 0.4064)
			(stroke
				(width 0.1524)
				(type default)
			)
			(layer "B.SilkS")
		)
		(fp_line
			(start 0.7874 0.4064)
			(end 0.7874 -0.4064)
			(stroke
				(width 0.1524)
				(type default)
			)
			(layer "B.SilkS")
		)
		(fp_line
			(start 0 0.381)
			(end 0 -0.381)
			(stroke
				(width 0.1524)
				(type default)
			)
			(layer "B.SilkS")
		)
		(fp_line
			(start -0.7874 -0.4064)
			(end -0.7874 0.4064)
			(stroke
				(width 0.1524)
				(type default)
			)
			(layer "B.SilkS")
		)
		(fp_line
			(start 0.7874 -0.4064)
			(end -0.7874 -0.4064)
			(stroke
				(width 0.1524)
				(type default)
			)
			(layer "B.SilkS")
		)
		(fp_poly
			(pts
				(xy 0.5334 0.254) (xy 0.635 0.254) (xy 0.635 0.2286) (xy 0.635 -0.254) (xy 0.5334 -0.254) (xy 0.5334 -0.2794)
				(xy -0.5334 -0.2794) (xy -0.5334 -0.254) (xy -0.635 -0.254) (xy -0.635 0.254) (xy -0.5334 0.254)
				(xy -0.5334 0.2794) (xy 0.508 0.2794) (xy 0.5334 0.2794)
			)
			(stroke
				(width 0)
				(type default)
			)
			(fill no)
			(layer "B.CrtYd")
		)
		(pad "1" smd rect
			(at -0.40005 0 90)
			(size 0.4572 0.508)
			(layers "B.Cu" "B.Mask" "B.Paste")
			(net "P3V3_NODE1")
		)
		(pad "2" smd rect
			(at 0.40005 0 90)
			(size 0.4572 0.508)
			(layers "B.Cu" "B.Mask" "B.Paste")
			(net "GND")
		)
	)
	(footprint ""
		(layer "B.Cu")
		(at 51.67376 -188.126624 -90)
		(property "Reference" "R854"
			(at -4.339082 -0.298704 270)
			(unlocked yes)
			(layer "B.SilkS")
			(effects
				(font
					(size 0.7874 0.5842)
					(thickness 0.1524)
				)
				(justify left mirror)
			)
		)
		(property "Value" ""
			(at 0 0 90)
			(layer "B.Fab")
			(effects
				(font
					(size 1.27 1.27)
				)
				(justify mirror)
			)
		)
		(duplicate_pad_numbers_are_jumpers no)
		(fp_line
			(start -0.7874 0.4064)
			(end 0.7874 0.4064)
			(stroke
				(width 0.1524)
				(type default)
			)
			(layer "B.SilkS")
		)
		(fp_line
			(start 0.7874 0.4064)
			(end 0.7874 -0.4064)
			(stroke
				(width 0.1524)
				(type default)
			)
			(layer "B.SilkS")
		)
		(fp_line
			(start -0.7874 -0.4064)
			(end -0.7874 0.4064)
			(stroke
				(width 0.1524)
				(type default)
			)
			(layer "B.SilkS")
		)
		(fp_line
			(start 0.7874 -0.4064)
			(end -0.7874 -0.4064)
			(stroke
				(width 0.1524)
				(type default)
			)
			(layer "B.SilkS")
		)
		(fp_poly
			(pts
				(xy 0.508 0.2794) (xy 0.508 0.2286) (xy 0.635 0.2286) (xy 0.635 -0.254) (xy 0.5334 -0.254) (xy 0.5334 -0.2794)
				(xy -0.5334 -0.2794) (xy -0.5334 -0.254) (xy -0.635 -0.254) (xy -0.635 0.254) (xy -0.5334 0.254)
				(xy -0.5334 0.2794)
			)
			(stroke
				(width 0)
				(type default)
			)
			(fill no)
			(layer "B.CrtYd")
		)
		(pad "1" smd rect
			(at -0.40005 0 90)
			(size 0.4572 0.508)
			(layers "B.Cu" "B.Mask" "B.Paste")
			(net "PSU2_DC_OK_R")
		)
		(pad "2" smd rect
			(at 0.40005 0 90)
			(size 0.4572 0.508)
			(layers "B.Cu" "B.Mask" "B.Paste")
			(net "GND")
		)
	)
	(footprint ""
		(layer "B.Cu")
		(at 123.70816 -172.378624 180)
		(property "Reference" "C570"
			(at 28.598876 -31.561024 0)
			(unlocked yes)
			(layer "B.SilkS")
			(effects
				(font
					(size 0.7874 0.5842)
					(thickness 0.1524)
				)
				(justify left mirror)
			)
		)
		(property "Value" ""
			(at 0 0 0)
			(layer "B.Fab")
			(effects
				(font
					(size 1.27 1.27)
				)
				(justify mirror)
			)
		)
		(duplicate_pad_numbers_are_jumpers no)
		(fp_line
			(start 0.7874 0.4064)
			(end 0.7874 -0.4064)
			(stroke
				(width 0.1524)
				(type default)
			)
			(layer "B.SilkS")
		)
		(fp_line
			(start 0.7874 -0.4064)
			(end -0.7874 -0.4064)
			(stroke
				(width 0.1524)
				(type default)
			)
			(layer "B.SilkS")
		)
		(fp_line
			(start 0 0.381)
			(end 0 -0.381)
			(stroke
				(width 0.1524)
				(type default)
			)
			(layer "B.SilkS")
		)
		(fp_line
			(start -0.7874 0.4064)
			(end 0.7874 0.4064)
			(stroke
				(width 0.1524)
				(type default)
			)
			(layer "B.SilkS")
		)
		(fp_line
			(start -0.7874 -0.4064)
			(end -0.7874 0.4064)
			(stroke
				(width 0.1524)
				(type default)
			)
			(layer "B.SilkS")
		)
		(fp_poly
			(pts
				(xy 0.5334 0.254) (xy 0.635 0.254) (xy 0.635 0.2286) (xy 0.635 -0.254) (xy 0.5334 -0.254) (xy 0.5334 -0.2794)
				(xy -0.5334 -0.2794) (xy -0.5334 -0.254) (xy -0.635 -0.254) (xy -0.635 0.254) (xy -0.5334 0.254)
				(xy -0.5334 0.2794) (xy 0.508 0.2794) (xy 0.5334 0.2794)
			)
			(stroke
				(width 0)
				(type default)
			)
			(fill no)
			(layer "B.CrtYd")
		)
		(pad "1" smd rect
			(at -0.40005 0)
			(size 0.4572 0.508)
			(layers "B.Cu" "B.Mask" "B.Paste")
			(net "GND")
		)
		(pad "2" smd rect
			(at 0.40005 0)
			(size 0.4572 0.508)
			(layers "B.Cu" "B.Mask" "B.Paste")
			(net "P3V3_NODE1")
		)
	)
	(footprint ""
		(layer "B.Cu")
		(at 125.892052 -145.21815 180)
		(property "Reference" "C880"
			(at 3.260598 3.302254 0)
			(unlocked yes)
			(layer "B.SilkS")
			(effects
				(font
					(size 0.7874 0.5842)
					(thickness 0.1524)
				)
				(justify left mirror)
			)
		)
		(property "Value" ""
			(at 0 0 0)
			(layer "B.Fab")
			(effects
				(font
					(size 1.27 1.27)
				)
				(justify mirror)
			)
		)
		(duplicate_pad_numbers_are_jumpers no)
		(fp_line
			(start 0.7874 0.4064)
			(end 0.7874 -0.4064)
			(stroke
				(width 0.1524)
				(type default)
			)
			(layer "B.SilkS")
		)
		(fp_line
			(start 0.7874 -0.4064)
			(end -0.7874 -0.4064)
			(stroke
				(width 0.1524)
				(type default)
			)
			(layer "B.SilkS")
		)
		(fp_line
			(start 0 0.381)
			(end 0 -0.381)
			(stroke
				(width 0.1524)
				(type default)
			)
			(layer "B.SilkS")
		)
		(fp_line
			(start -0.7874 0.4064)
			(end 0.7874 0.4064)
			(stroke
				(width 0.1524)
				(type default)
			)
			(layer "B.SilkS")
		)
		(fp_line
			(start -0.7874 -0.4064)
			(end -0.7874 0.4064)
			(stroke
				(width 0.1524)
				(type default)
			)
			(layer "B.SilkS")
		)
		(fp_poly
			(pts
				(xy 0.5334 0.254) (xy 0.635 0.254) (xy 0.635 0.2286) (xy 0.635 -0.254) (xy 0.5334 -0.254) (xy 0.5334 -0.2794)
				(xy -0.5334 -0.2794) (xy -0.5334 -0.254) (xy -0.635 -0.254) (xy -0.635 0.254) (xy -0.5334 0.254)
				(xy -0.5334 0.2794) (xy 0.508 0.2794) (xy 0.5334 0.2794)
			)
			(stroke
				(width 0)
				(type default)
			)
			(fill no)
			(layer "B.CrtYd")
		)
		(pad "1" smd rect
			(at -0.40005 0)
			(size 0.4572 0.508)
			(layers "B.Cu" "B.Mask" "B.Paste")
			(net "P1V0_NODE1")
		)
		(pad "2" smd rect
			(at 0.40005 0)
			(size 0.4572 0.508)
			(layers "B.Cu" "B.Mask" "B.Paste")
			(net "GND")
		)
	)
	(footprint ""
		(layer "B.Cu")
		(at 155.05176 -187.872624 -90)
		(property "Reference" "C648"
			(at -4.565396 3.650742 270)
			(unlocked yes)
			(layer "B.SilkS")
			(effects
				(font
					(size 0.7874 0.5842)
					(thickness 0.1524)
				)
				(justify left mirror)
			)
		)
		(property "Value" ""
			(at 0 0 90)
			(layer "B.Fab")
			(effects
				(font
					(size 1.27 1.27)
				)
				(justify mirror)
			)
		)
		(duplicate_pad_numbers_are_jumpers no)
		(fp_line
			(start -0.7874 0.4064)
			(end 0.7874 0.4064)
			(stroke
				(width 0.1524)
				(type default)
			)
			(layer "B.SilkS")
		)
		(fp_line
			(start 0.7874 0.4064)
			(end 0.7874 -0.4064)
			(stroke
				(width 0.1524)
				(type default)
			)
			(layer "B.SilkS")
		)
		(fp_line
			(start 0 0.381)
			(end 0 -0.381)
			(stroke
				(width 0.1524)
				(type default)
			)
			(layer "B.SilkS")
		)
		(fp_line
			(start -0.7874 -0.4064)
			(end -0.7874 0.4064)
			(stroke
				(width 0.1524)
				(type default)
			)
			(layer "B.SilkS")
		)
		(fp_line
			(start 0.7874 -0.4064)
			(end -0.7874 -0.4064)
			(stroke
				(width 0.1524)
				(type default)
			)
			(layer "B.SilkS")
		)
		(fp_poly
			(pts
				(xy 0.5334 0.254) (xy 0.635 0.254) (xy 0.635 0.2286) (xy 0.635 -0.254) (xy 0.5334 -0.254) (xy 0.5334 -0.2794)
				(xy -0.5334 -0.2794) (xy -0.5334 -0.254) (xy -0.635 -0.254) (xy -0.635 0.254) (xy -0.5334 0.254)
				(xy -0.5334 0.2794) (xy 0.508 0.2794) (xy 0.5334 0.2794)
			)
			(stroke
				(width 0)
				(type default)
			)
			(fill no)
			(layer "B.CrtYd")
		)
		(pad "1" smd rect
			(at -0.40005 0 90)
			(size 0.4572 0.508)
			(layers "B.Cu" "B.Mask" "B.Paste")
			(net "T11_NODE1_EN_R")
		)
		(pad "2" smd rect
			(at 0.40005 0 90)
			(size 0.4572 0.508)
			(layers "B.Cu" "B.Mask" "B.Paste")
			(net "GND")
		)
	)
)
